# SCM (Grand Teton) — schematic netlist excerpt (pin names and nets, part order shuffled) for the footprints in the layout excerpt that follows; sources: Cadence DE-HDL packaged netlist, KiCad conversion of 12092022_DA0F0TMDCD0_F0T_Management_Board_D_brd_V3_OCP.brd

R300  Q_RES  33.2 1% CHIP  pkg 0402LF  page 28 : A = SMB_DEBUG_AUX_LVC3_USB_R1_SCL ; B = SMB_DEBUG_AUX_LVC3_USB_SCL
C335  Q_CAP  1UF 25V 10% X6S  pkg C0402  page 50 : A = REAR_AC_PWR_BMC_BTN_N ; B = GND

(kicad_pcb
	(version 20260206)
	(generator "pcbnew")
	(generator_version "10.0")
	(general
		(thickness 1.6)
		(legacy_teardrops no)
	)
	(paper "A4")
	(title_block
		(title "12092022_DA0F0TMDCD0_F0T_Management_Board_D_brd_V3_OCP.brd")
		(comment 1 "Grand Teton / footprints 771-772 of 1440")
	)
	(layers
		(0 "F.Cu" signal "TOP")
		(4 "In1.Cu" signal "GND")
		(6 "In2.Cu" signal "IN1")
		(8 "In3.Cu" signal "GND1")
		(10 "In4.Cu" signal "IN2")
		(12 "In5.Cu" signal "VCC")
		(14 "In6.Cu" signal "VCC1")
		(16 "In7.Cu" signal "IN3")
		(18 "In8.Cu" signal "GND2")
		(20 "In9.Cu" signal "IN4")
		(22 "In10.Cu" signal "GND3")
		(2 "B.Cu" signal "BOTTOM")
		(9 "F.Adhes" user "F.Adhesive")
		(11 "B.Adhes" user "B.Adhesive")
		(13 "F.Paste" user "Package Geometry/Pastemask Top")
		(15 "B.Paste" user "Package Geometry/Pastemask Bottom")
		(5 "F.SilkS" user "Ref Des/Silkscreen Top")
		(7 "B.SilkS" user "Ref Des/Silkscreen Bottom")
		(1 "F.Mask" user "Board Geometry/Soldermask Top")
		(3 "B.Mask" user "Board Geometry/Soldermask Bottom")
		(17 "Dwgs.User" user "User.Drawings")
		(19 "Cmts.User" user "User.Comments")
		(21 "Eco1.User" user "User.Eco1")
		(23 "Eco2.User" user "User.Eco2")
		(25 "Edge.Cuts" user "Board Geometry/Outline")
		(27 "Margin" user)
		(31 "F.CrtYd" user "Package Geometry/Place Bound Top")
		(29 "B.CrtYd" user "Package Geometry/Place Bound Bottom")
		(35 "F.Fab" user "Ref Des/Assembly Top")
		(33 "B.Fab" user "Ref Des/Assembly Bottom")
	)
	(footprint ""
		(layer "B.Cu")
		(at 18.2118 -72.9234 180)
		(property "Reference" "R300"
			(at 0 0 0)
			(layer "B.SilkS")
			(hide yes)
			(effects
				(font
					(size 1.27 1.27)
				)
				(justify mirror)
			)
		)
		(property "Value" ""
			(at 0 0 0)
			(layer "B.Fab")
			(effects
				(font
					(size 1.27 1.27)
				)
				(justify mirror)
			)
		)
		(duplicate_pad_numbers_are_jumpers no)
		(fp_line
			(start 0.7874 0.4064)
			(end 0.7874 -0.4064)
			(stroke
				(width 0.1524)
				(type default)
			)
			(layer "B.SilkS")
		)
		(fp_line
			(start 0.7874 -0.4064)
			(end -0.7874 -0.4064)
			(stroke
				(width 0.1524)
				(type default)
			)
			(layer "B.SilkS")
		)
		(fp_line
			(start -0.7874 0.4064)
			(end 0.7874 0.4064)
			(stroke
				(width 0.1524)
				(type default)
			)
			(layer "B.SilkS")
		)
		(fp_line
			(start -0.7874 -0.4064)
			(end -0.7874 0.4064)
			(stroke
				(width 0.1524)
				(type default)
			)
			(layer "B.SilkS")
		)
		(fp_line
			(start 0.67945 0.3048)
			(end 0.67945 -0.305054)
			(stroke
				(width 0.1)
				(type default)
			)
			(layer "B.Fab")
		)
		(fp_line
			(start 0.67945 -0.305054)
			(end 0.12065 -0.305054)
			(stroke
				(width 0.1)
				(type default)
			)
			(layer "B.Fab")
		)
		(fp_line
			(start 0.12065 0.3048)
			(end 0.67945 0.3048)
			(stroke
				(width 0.1)
				(type default)
			)
			(layer "B.Fab")
		)
		(fp_line
			(start 0.12065 0.2794)
			(end 0.12065 0.3048)
			(stroke
				(width 0.1)
				(type default)
			)
			(layer "B.Fab")
		)
		(fp_line
			(start 0.12065 -0.2794)
			(end -0.12065 -0.2794)
			(stroke
				(width 0.1)
				(type default)
			)
			(layer "B.Fab")
		)
		(fp_line
			(start 0.12065 -0.305054)
			(end 0.12065 -0.2794)
			(stroke
				(width 0.1)
				(type default)
			)
			(layer "B.Fab")
		)
		(fp_line
			(start -0.120396 0.3048)
			(end -0.120396 0.2794)
			(stroke
				(width 0.1)
				(type default)
			)
			(layer "B.Fab")
		)
		(fp_line
			(start -0.120396 0.2794)
			(end 0.12065 0.2794)
			(stroke
				(width 0.1)
				(type default)
			)
			(layer "B.Fab")
		)
		(fp_line
			(start -0.12065 -0.2794)
			(end -0.12065 -0.3048)
			(stroke
				(width 0.1)
				(type default)
			)
			(layer "B.Fab")
		)
		(fp_line
			(start -0.12065 -0.3048)
			(end -0.67945 -0.3048)
			(stroke
				(width 0.1)
				(type default)
			)
			(layer "B.Fab")
		)
		(fp_line
			(start -0.67945 0.3048)
			(end -0.120396 0.3048)
			(stroke
				(width 0.1)
				(type default)
			)
			(layer "B.Fab")
		)
		(fp_line
			(start -0.67945 -0.3048)
			(end -0.67945 0.3048)
			(stroke
				(width 0.1)
				(type default)
			)
			(layer "B.Fab")
		)
		(pad "1" smd circle
			(at 0.40005 0)
			(size 0 0)
			(layers "B.Cu" "B.Mask" "B.Paste")
			(net "SMB_DEBUG_AUX_LVC3_USB_R1_SCL")
		)
		(pad "2" smd circle
			(at -0.40005 0)
			(size 0 0)
			(layers "B.Cu" "B.Mask" "B.Paste")
			(net "SMB_DEBUG_AUX_LVC3_USB_SCL")
		)
	)
	(footprint ""
		(layer "B.Cu")
		(at 68.58 -12.446 180)
		(property "Reference" "C335"
			(at 0 0 0)
			(layer "B.SilkS")
			(hide yes)
			(effects
				(font
					(size 1.27 1.27)
				)
				(justify mirror)
			)
		)
		(property "Value" ""
			(at 0 0 0)
			(layer "B.Fab")
			(effects
				(font
					(size 1.27 1.27)
				)
				(justify mirror)
			)
		)
		(duplicate_pad_numbers_are_jumpers no)
		(fp_line
			(start 0.7874 0.4064)
			(end 0.7874 -0.4064)
			(stroke
				(width 0.1524)
				(type default)
			)
			(layer "B.SilkS")
		)
		(fp_line
			(start 0.7874 -0.4064)
			(end -0.7874 -0.4064)
			(stroke
				(width 0.1524)
				(type default)
			)
			(layer "B.SilkS")
		)
		(fp_line
			(start -0.7874 0.4064)
			(end 0.7874 0.4064)
			(stroke
				(width 0.1524)
				(type default)
			)
			(layer "B.SilkS")
		)
		(fp_line
			(start -0.7874 -0.4064)
			(end -0.7874 0.4064)
			(stroke
				(width 0.1524)
				(type default)
			)
			(layer "B.SilkS")
		)
		(fp_line
			(start 0.67945 0.3048)
			(end 0.67945 -0.305054)
			(stroke
				(width 0.1)
				(type default)
			)
			(layer "B.Fab")
		)
		(fp_line
			(start 0.67945 -0.305054)
			(end 0.12065 -0.305054)
			(stroke
				(width 0.1)
				(type default)
			)
			(layer "B.Fab")
		)
		(fp_line
			(start 0.12065 0.3048)
			(end 0.67945 0.3048)
			(stroke
				(width 0.1)
				(type default)
			)
			(layer "B.Fab")
		)
		(fp_line
			(start 0.12065 0.2794)
			(end 0.12065 0.3048)
			(stroke
				(width 0.1)
				(type default)
			)
			(layer "B.Fab")
		)
		(fp_line
			(start 0.12065 -0.2794)
			(end -0.12065 -0.2794)
			(stroke
				(width 0.1)
				(type default)
			)
			(layer "B.Fab")
		)
		(fp_line
			(start 0.12065 -0.305054)
			(end 0.12065 -0.2794)
			(stroke
				(width 0.1)
				(type default)
			)
			(layer "B.Fab")
		)
		(fp_line
			(start -0.120396 0.3048)
			(end -0.120396 0.2794)
			(stroke
				(width 0.1)
				(type default)
			)
			(layer "B.Fab")
		)
		(fp_line
			(start -0.120396 0.2794)
			(end 0.12065 0.2794)
			(stroke
				(width 0.1)
				(type default)
			)
			(layer "B.Fab")
		)
		(fp_line
			(start -0.12065 -0.2794)
			(end -0.12065 -0.3048)
			(stroke
				(width 0.1)
				(type default)
			)
			(layer "B.Fab")
		)
		(fp_line
			(start -0.12065 -0.3048)
			(end -0.67945 -0.3048)
			(stroke
				(width 0.1)
				(type default)
			)
			(layer "B.Fab")
		)
		(fp_line
			(start -0.67945 0.3048)
			(end -0.120396 0.3048)
			(stroke
				(width 0.1)
				(type default)
			)
			(layer "B.Fab")
		)
		(fp_line
			(start -0.67945 -0.3048)
			(end -0.67945 0.3048)
			(stroke
				(width 0.1)
				(type default)
			)
			(layer "B.Fab")
		)
		(pad "1" smd circle
			(at 0.40005 0)
			(size 0 0)
			(layers "B.Cu" "B.Mask" "B.Paste")
			(net "REAR_AC_PWR_BMC_BTN_N")
		)
		(pad "2" smd circle
			(at -0.40005 0)
			(size 0 0)
			(layers "B.Cu" "B.Mask" "B.Paste")
			(net "GND")
		)
	)
)
